# BASEBOARD_FAB2 (Tioga Pass) — schematic netlist excerpt (pin names and nets, part order shuffled) for the footprints in the layout excerpt that follows; sources: Cadence DE-HDL packaged netlist, KiCad conversion of Wiwynn_Tioga_Pass_MB.brd

C3D24  CAP_A  22.0UF 4V 20% X6S  pkg 0603V  page 76 : A = PVCCIO_CPU1 ; B = GND
C30W7  SC22U16V5MX-4-GP  20%  pkg SMD-BCG5  page 253 : \1\ = P5V_STBY_USBC ; \2\ = GND
C22W16  SC22U16V5MX-4-GP  20%  pkg SMD-BCG5  page 214 : \1\ = VR_FET_SW_P12V_STBY_PVCCIN_CPU0 ; \2\ = GND
R7B14  RES  7.87K 1.0% CHIP  pkg 0402  page 232 : A = VR_PVPP_DEF_ISET ; B = AGND_PVPP_DEF

(kicad_pcb
	(version 20260206)
	(generator "pcbnew")
	(generator_version "10.0")
	(general
		(thickness 1.6)
		(legacy_teardrops no)
	)
	(paper "A4")
	(title_block
		(title "Wiwynn_Tioga_Pass_MB.brd")
		(comment 1 "Tioga Pass / footprints 1315-1318 of 4770")
	)
	(layers
		(0 "F.Cu" signal "TOP")
		(4 "In1.Cu" signal "L2GND")
		(6 "In2.Cu" signal "L3")
		(8 "In3.Cu" signal "L4GND")
		(10 "In4.Cu" signal "L5")
		(12 "In5.Cu" signal "L6GND")
		(14 "In6.Cu" signal "L7VCC")
		(16 "In7.Cu" signal "L8VCC")
		(18 "In8.Cu" signal "L9GND")
		(20 "In9.Cu" signal "L10")
		(22 "In10.Cu" signal "L11GND")
		(24 "In11.Cu" signal "L12")
		(26 "In12.Cu" signal "L13GND")
		(2 "B.Cu" signal "BOTTOM")
		(9 "F.Adhes" user "F.Adhesive")
		(11 "B.Adhes" user "B.Adhesive")
		(13 "F.Paste" user "Package Geometry/Pastemask Top")
		(15 "B.Paste" user "Package Geometry/Pastemask Bottom")
		(5 "F.SilkS" user "Ref Des/Silkscreen Top")
		(7 "B.SilkS" user "Ref Des/Silkscreen Bottom")
		(1 "F.Mask" user "Board Geometry/Soldermask Top")
		(3 "B.Mask" user "Board Geometry/Soldermask Bottom")
		(17 "Dwgs.User" user "User.Drawings")
		(19 "Cmts.User" user "User.Comments")
		(21 "Eco1.User" user "User.Eco1")
		(23 "Eco2.User" user "User.Eco2")
		(25 "Edge.Cuts" user "Board Geometry/Outline")
		(27 "Margin" user)
		(31 "F.CrtYd" user "Package Geometry/Place Bound Top")
		(29 "B.CrtYd" user "Package Geometry/Place Bound Bottom")
		(35 "F.Fab" user "Ref Des/Assembly Top")
		(33 "B.Fab" user "Ref Des/Assembly Bottom")
	)
	(footprint ""
		(layer "F.Cu")
		(at 490.3724 -59.944 180)
		(property "Reference" "C30W7"
			(at 0 0 180)
			(layer "F.SilkS")
			(hide yes)
			(effects
				(font
					(size 1.27 1.27)
				)
			)
		)
		(property "Value" "*"
			(at -0.0762 -6.2357 180)
			(unlocked yes)
			(layer "F.Fab")
			(hide yes)
			(effects
				(font
					(size 1.27 1.016)
					(thickness 0.1524)
				)
			)
		)
		(property "Device Type" "SC22U16V5MX-4-GP_SMD-BCG5-SC22A"
			(at -0.0762 -8.2677 180)
			(unlocked yes)
			(layer "F.Fab")
			(hide yes)
			(effects
				(font
					(size 1.27 1.016)
					(thickness 0.1524)
				)
			)
		)
		(duplicate_pad_numbers_are_jumpers no)
		(fp_line
			(start 0.635 0)
			(end -0.635 0)
			(stroke
				(width 0.508)
				(type default)
			)
			(layer "F.SilkS")
		)
		(fp_rect
			(start -0.9652 1.778)
			(end 0.9652 -1.778)
			(stroke
				(width 0)
				(type default)
			)
			(fill no)
			(layer "F.CrtYd")
		)
		(fp_poly
			(pts
				(xy -0.9652 -1.778) (xy 0.9652 -1.778) (xy 0.9652 1.778) (xy -0.9652 1.778)
			)
			(stroke
				(width 0)
				(type default)
			)
			(fill no)
			(layer "F.Fab")
		)
		(pad "1" smd rect
			(at 0 -0.9652 180)
			(size 1.397 1.143)
			(layers "F.Cu" "F.Mask" "F.Paste")
			(net "P5V_STBY_USBC")
		)
		(pad "2" smd rect
			(at 0 0.9652 180)
			(size 1.397 1.143)
			(layers "F.Cu" "F.Mask" "F.Paste")
			(net "GND")
		)
	)
	(footprint ""
		(layer "F.Cu")
		(at 344.043 -127.4572 90)
		(property "Reference" "R7B14"
			(at 0 0 90)
			(layer "F.SilkS")
			(hide yes)
			(effects
				(font
					(size 1.27 1.27)
				)
			)
		)
		(property "Value" ""
			(at 0 0 90)
			(layer "F.Fab")
			(effects
				(font
					(size 1.27 1.27)
				)
			)
		)
		(duplicate_pad_numbers_are_jumpers no)
		(fp_poly
			(pts
				(xy -0.2794 -0.1016) (xy 0.2794 -0.1016) (xy 0.2794 0.9906) (xy -0.2794 0.9906)
			)
			(stroke
				(width 0)
				(type default)
			)
			(fill no)
			(layer "F.CrtYd")
		)
		(fp_line
			(start 0.2794 -0.1016)
			(end -0.2794 -0.1016)
			(stroke
				(width 0.1)
				(type default)
			)
			(layer "F.Fab")
		)
		(fp_line
			(start -0.2794 -0.1016)
			(end -0.2794 0.9906)
			(stroke
				(width 0.1)
				(type default)
			)
			(layer "F.Fab")
		)
		(fp_line
			(start 0.2794 0.9906)
			(end 0.2794 -0.1016)
			(stroke
				(width 0.1)
				(type default)
			)
			(layer "F.Fab")
		)
		(fp_line
			(start -0.2794 0.9906)
			(end 0.2794 0.9906)
			(stroke
				(width 0.1)
				(type default)
			)
			(layer "F.Fab")
		)
		(pad "1" smd rect
			(at 0 0 90)
			(size 0.508 0.508)
			(layers "F.Cu" "F.Mask" "F.Paste")
			(net "VR_PVPP_DEF_ISET")
		)
		(pad "2" smd rect
			(at 0 0.889 90)
			(size 0.508 0.508)
			(layers "F.Cu" "F.Mask" "F.Paste")
			(net "AGND_PVPP_DEF")
		)
		(zone
			(layer "F.Cu")
			(hatch none 0.5)
			(connect_pads
				(clearance 0)
			)
			(min_thickness 0.25)
			(keepout
				(tracks allowed)
				(vias not_allowed)
				(pads allowed)
				(copperpour not_allowed)
				(footprints allowed)
			)
			(placement
				(enabled no)
				(sheetname "")
			)
			(fill
				(thermal_gap 0.5)
				(thermal_bridge_width 0.5)
				(island_removal_mode 0)
			)
			(polygon
				(pts
					(xy 344.297 -127.2032) (xy 344.297 -127.7112) (xy 344.678 -127.7112) (xy 344.678 -127.2032)
				)
			)
		)
		(zone
			(layer "F.Cu")
			(hatch none 0.5)
			(connect_pads
				(clearance 0)
			)
			(min_thickness 0.25)
			(keepout
				(tracks not_allowed)
				(vias allowed)
				(pads allowed)
				(copperpour not_allowed)
				(footprints allowed)
			)
			(placement
				(enabled no)
				(sheetname "")
			)
			(fill
				(thermal_gap 0.5)
				(thermal_bridge_width 0.5)
				(island_removal_mode 0)
			)
			(polygon
				(pts
					(xy 344.678 -127.2032) (xy 344.678 -127.7112) (xy 344.297 -127.7112) (xy 344.297 -127.2032)
				)
			)
		)
	)
	(footprint ""
		(layer "F.Cu")
		(at 115.137692 -71.714614 180)
		(property "Reference" "C3D24"
			(at 0 0 180)
			(layer "F.SilkS")
			(hide yes)
			(effects
				(font
					(size 1.27 1.27)
				)
			)
		)
		(property "Value" ""
			(at 0 0 180)
			(layer "F.Fab")
			(effects
				(font
					(size 1.27 1.27)
				)
			)
		)
		(duplicate_pad_numbers_are_jumpers no)
		(fp_poly
			(pts
				(xy -0.4953 -0.2032) (xy 0.4953 -0.2032) (xy 0.4953 1.6002) (xy -0.4953 1.6002)
			)
			(stroke
				(width 0)
				(type default)
			)
			(fill no)
			(layer "F.CrtYd")
		)
		(fp_line
			(start 0.4953 1.6002)
			(end -0.4953 1.6002)
			(stroke
				(width 0.1)
				(type default)
			)
			(layer "F.Fab")
		)
		(fp_line
			(start 0.4953 -0.2032)
			(end 0.4953 1.6002)
			(stroke
				(width 0.1)
				(type default)
			)
			(layer "F.Fab")
		)
		(fp_line
			(start -0.4953 1.6002)
			(end -0.4953 -0.2032)
			(stroke
				(width 0.1)
				(type default)
			)
			(layer "F.Fab")
		)
		(fp_line
			(start -0.4953 -0.2032)
			(end 0.4953 -0.2032)
			(stroke
				(width 0.1)
				(type default)
			)
			(layer "F.Fab")
		)
		(pad "1" smd rect
			(at 0 0 180)
			(size 0.762 0.889)
			(layers "F.Cu" "F.Mask" "F.Paste")
			(net "PVCCIO_CPU1")
		)
		(pad "2" smd rect
			(at 0 1.397 180)
			(size 0.762 0.889)
			(layers "F.Cu" "F.Mask" "F.Paste")
			(net "GND")
		)
		(zone
			(layer "F.Cu")
			(hatch none 0.5)
			(connect_pads
				(clearance 0)
			)
			(min_thickness 0.25)
			(keepout
				(tracks not_allowed)
				(vias allowed)
				(pads allowed)
				(copperpour not_allowed)
				(footprints allowed)
			)
			(placement
				(enabled no)
				(sheetname "")
			)
			(fill
				(thermal_gap 0.5)
				(thermal_bridge_width 0.5)
				(island_removal_mode 0)
			)
			(polygon
				(pts
					(xy 115.518692 -72.159114) (xy 114.756692 -72.159114) (xy 114.756692 -72.667114) (xy 115.518692 -72.667114)
				)
			)
		)
	)
	(footprint ""
		(layer "F.Cu")
		(at 181.63413 -61.03112 180)
		(property "Reference" "C22W16"
			(at 0 0 180)
			(layer "F.SilkS")
			(hide yes)
			(effects
				(font
					(size 1.27 1.27)
				)
			)
		)
		(property "Value" "*"
			(at -0.0762 -6.2357 180)
			(unlocked yes)
			(layer "F.Fab")
			(hide yes)
			(effects
				(font
					(size 1.27 1.016)
					(thickness 0.1524)
				)
			)
		)
		(property "Device Type" "SC22U16V5MX-4-GP_SMD-BCG5-SC22A"
			(at -0.0762 -8.2677 180)
			(unlocked yes)
			(layer "F.Fab")
			(hide yes)
			(effects
				(font
					(size 1.27 1.016)
					(thickness 0.1524)
				)
			)
		)
		(duplicate_pad_numbers_are_jumpers no)
		(fp_line
			(start 0.635 0)
			(end -0.635 0)
			(stroke
				(width 0.508)
				(type default)
			)
			(layer "F.SilkS")
		)
		(fp_rect
			(start -0.9652 1.778)
			(end 0.9652 -1.778)
			(stroke
				(width 0)
				(type default)
			)
			(fill no)
			(layer "F.CrtYd")
		)
		(fp_poly
			(pts
				(xy -0.9652 -1.778) (xy 0.9652 -1.778) (xy 0.9652 1.778) (xy -0.9652 1.778)
			)
			(stroke
				(width 0)
				(type default)
			)
			(fill no)
			(layer "F.Fab")
		)
		(pad "1" smd rect
			(at 0 -0.9652 180)
			(size 1.397 1.143)
			(layers "F.Cu" "F.Mask" "F.Paste")
			(net "VR_FET_SW_P12V_STBY_PVCCIN_CPU0")
		)
		(pad "2" smd rect
			(at 0 0.9652 180)
			(size 1.397 1.143)
			(layers "F.Cu" "F.Mask" "F.Paste")
			(net "GND")
		)
	)
)
